(kicad_pcb
	(version 20260206)
	(generator "pcbnew")
	(generator_version "10.0")
	(general
		(thickness 1.6)
		(legacy_teardrops no)
	)
	(paper "A4")
	(title_block
		(title "04192023_DAF0TMB3IC0_F0TG_MB_C_brd_V02_OCP.brd")
		(comment 1 "Grand Teton / footprints 1857-1863 of 8354")
	)
	(layers
		(0 "F.Cu" signal "TOP")
		(4 "In1.Cu" signal "GND")
		(6 "In2.Cu" signal "IN1")
		(8 "In3.Cu" signal "GND1")
		(10 "In4.Cu" signal "IN2")
		(12 "In5.Cu" signal "GND2")
		(14 "In6.Cu" signal "IN3")
		(16 "In7.Cu" signal "GND3")
		(18 "In8.Cu" signal "VCC")
		(20 "In9.Cu" signal "VCC1")
		(22 "In10.Cu" signal "GND4")
		(24 "In11.Cu" signal "IN4")
		(26 "In12.Cu" signal "GND5")
		(28 "In13.Cu" signal "IN5")
		(30 "In14.Cu" signal "GND6")
		(32 "In15.Cu" signal "IN6")
		(34 "In16.Cu" signal "GND7")
		(2 "B.Cu" signal "BOTTOM")
		(9 "F.Adhes" user "F.Adhesive")
		(11 "B.Adhes" user "B.Adhesive")
		(13 "F.Paste" user "Package Geometry/Pastemask Top")
		(15 "B.Paste" user "Package Geometry/Pastemask Bottom")
		(5 "F.SilkS" user "Ref Des/Silkscreen Top")
		(7 "B.SilkS" user "Ref Des/Silkscreen Bottom")
		(1 "F.Mask" user "Board Geometry/Soldermask Top")
		(3 "B.Mask" user "Board Geometry/Soldermask Bottom")
		(17 "Dwgs.User" user "User.Drawings")
		(19 "Cmts.User" user "User.Comments")
		(21 "Eco1.User" user "User.Eco1")
		(23 "Eco2.User" user "User.Eco2")
		(25 "Edge.Cuts" user "Board Geometry/Outline")
		(27 "Margin" user)
		(31 "F.CrtYd" user "Package Geometry/Place Bound Top")
		(29 "B.CrtYd" user "Package Geometry/Place Bound Bottom")
		(35 "F.Fab" user "Ref Des/Assembly Top")
		(33 "B.Fab" user "Ref Des/Assembly Bottom")
	)
	(footprint ""
		(layer "F.Cu")
		(at 22.49805 -333.151226)
		(property "Reference" "PR460"
			(at 0 0 0)
			(layer "F.SilkS")
			(hide yes)
			(effects
				(font
					(size 1.27 1.27)
				)
			)
		)
		(property "Value" ""
			(at 0 0 0)
			(layer "F.Fab")
			(effects
				(font
					(size 1.27 1.27)
				)
			)
		)
		(duplicate_pad_numbers_are_jumpers no)
		(fp_line
			(start -0.7874 -0.4064)
			(end 0.7874 -0.4064)
			(stroke
				(width 0.1524)
				(type default)
			)
			(layer "F.SilkS")
		)
		(fp_line
			(start -0.7874 0.4064)
			(end -0.7874 -0.4064)
			(stroke
				(width 0.1524)
				(type default)
			)
			(layer "F.SilkS")
		)
		(fp_line
			(start 0.7874 -0.4064)
			(end 0.7874 0.4064)
			(stroke
				(width 0.1524)
				(type default)
			)
			(layer "F.SilkS")
		)
		(fp_line
			(start 0.7874 0.4064)
			(end -0.7874 0.4064)
			(stroke
				(width 0.1524)
				(type default)
			)
			(layer "F.SilkS")
		)
		(fp_line
			(start -0.67945 -0.305054)
			(end -0.12065 -0.305054)
			(stroke
				(width 0.1)
				(type default)
			)
			(layer "F.Fab")
		)
		(fp_line
			(start -0.67945 0.3048)
			(end -0.67945 -0.305054)
			(stroke
				(width 0.1)
				(type default)
			)
			(layer "F.Fab")
		)
		(fp_line
			(start -0.12065 -0.305054)
			(end -0.12065 -0.2794)
			(stroke
				(width 0.1)
				(type default)
			)
			(layer "F.Fab")
		)
		(fp_line
			(start -0.12065 -0.2794)
			(end 0.12065 -0.2794)
			(stroke
				(width 0.1)
				(type default)
			)
			(layer "F.Fab")
		)
		(fp_line
			(start -0.12065 0.2794)
			(end -0.12065 0.3048)
			(stroke
				(width 0.1)
				(type default)
			)
			(layer "F.Fab")
		)
		(fp_line
			(start -0.12065 0.3048)
			(end -0.67945 0.3048)
			(stroke
				(width 0.1)
				(type default)
			)
			(layer "F.Fab")
		)
		(fp_line
			(start 0.120396 0.2794)
			(end -0.12065 0.2794)
			(stroke
				(width 0.1)
				(type default)
			)
			(layer "F.Fab")
		)
		(fp_line
			(start 0.120396 0.3048)
			(end 0.120396 0.2794)
			(stroke
				(width 0.1)
				(type default)
			)
			(layer "F.Fab")
		)
		(fp_line
			(start 0.12065 -0.3048)
			(end 0.67945 -0.3048)
			(stroke
				(width 0.1)
				(type default)
			)
			(layer "F.Fab")
		)
		(fp_line
			(start 0.12065 -0.2794)
			(end 0.12065 -0.3048)
			(stroke
				(width 0.1)
				(type default)
			)
			(layer "F.Fab")
		)
		(fp_line
			(start 0.67945 -0.3048)
			(end 0.67945 0.3048)
			(stroke
				(width 0.1)
				(type default)
			)
			(layer "F.Fab")
		)
		(fp_line
			(start 0.67945 0.3048)
			(end 0.120396 0.3048)
			(stroke
				(width 0.1)
				(type default)
			)
			(layer "F.Fab")
		)
		(pad "1" smd circle
			(at -0.40005 0)
			(size 0 0)
			(layers "F.Cu" "F.Mask" "F.Paste")
			(net "VSENSE_VSS_SENSE_B_P1")
		)
		(pad "2" smd circle
			(at 0.40005 0)
			(size 0 0)
			(layers "F.Cu" "F.Mask" "F.Paste")
			(net "GND")
		)
	)
	(footprint ""
		(layer "F.Cu")
		(at 105.960164 -262.205216 180)
		(property "Reference" "C3920"
			(at 0 0 180)
			(layer "F.SilkS")
			(hide yes)
			(effects
				(font
					(size 1.27 1.27)
				)
			)
		)
		(property "Value" ""
			(at 0 0 180)
			(layer "F.Fab")
			(effects
				(font
					(size 1.27 1.27)
				)
			)
		)
		(duplicate_pad_numbers_are_jumpers no)
		(fp_line
			(start 0.7874 0.4064)
			(end -0.7874 0.4064)
			(stroke
				(width 0.1524)
				(type default)
			)
			(layer "F.SilkS")
		)
		(fp_line
			(start 0.7874 -0.4064)
			(end 0.7874 0.4064)
			(stroke
				(width 0.1524)
				(type default)
			)
			(layer "F.SilkS")
		)
		(fp_line
			(start -0.7874 0.4064)
			(end -0.7874 -0.4064)
			(stroke
				(width 0.1524)
				(type default)
			)
			(layer "F.SilkS")
		)
		(fp_line
			(start -0.7874 -0.4064)
			(end 0.7874 -0.4064)
			(stroke
				(width 0.1524)
				(type default)
			)
			(layer "F.SilkS")
		)
		(fp_line
			(start 0.67945 0.3048)
			(end 0.120396 0.3048)
			(stroke
				(width 0.1)
				(type default)
			)
			(layer "F.Fab")
		)
		(fp_line
			(start 0.67945 -0.3048)
			(end 0.67945 0.3048)
			(stroke
				(width 0.1)
				(type default)
			)
			(layer "F.Fab")
		)
		(fp_line
			(start 0.12065 -0.2794)
			(end 0.12065 -0.3048)
			(stroke
				(width 0.1)
				(type default)
			)
			(layer "F.Fab")
		)
		(fp_line
			(start 0.12065 -0.3048)
			(end 0.67945 -0.3048)
			(stroke
				(width 0.1)
				(type default)
			)
			(layer "F.Fab")
		)
		(fp_line
			(start 0.120396 0.3048)
			(end 0.120396 0.2794)
			(stroke
				(width 0.1)
				(type default)
			)
			(layer "F.Fab")
		)
		(fp_line
			(start 0.120396 0.2794)
			(end -0.12065 0.2794)
			(stroke
				(width 0.1)
				(type default)
			)
			(layer "F.Fab")
		)
		(fp_line
			(start -0.12065 0.3048)
			(end -0.67945 0.3048)
			(stroke
				(width 0.1)
				(type default)
			)
			(layer "F.Fab")
		)
		(fp_line
			(start -0.12065 0.2794)
			(end -0.12065 0.3048)
			(stroke
				(width 0.1)
				(type default)
			)
			(layer "F.Fab")
		)
		(fp_line
			(start -0.12065 -0.2794)
			(end 0.12065 -0.2794)
			(stroke
				(width 0.1)
				(type default)
			)
			(layer "F.Fab")
		)
		(fp_line
			(start -0.12065 -0.305054)
			(end -0.12065 -0.2794)
			(stroke
				(width 0.1)
				(type default)
			)
			(layer "F.Fab")
		)
		(fp_line
			(start -0.67945 0.3048)
			(end -0.67945 -0.305054)
			(stroke
				(width 0.1)
				(type default)
			)
			(layer "F.Fab")
		)
		(fp_line
			(start -0.67945 -0.305054)
			(end -0.12065 -0.305054)
			(stroke
				(width 0.1)
				(type default)
			)
			(layer "F.Fab")
		)
		(pad "1" smd circle
			(at -0.40005 0 180)
			(size 0 0)
			(layers "F.Cu" "F.Mask" "F.Paste")
			(net "PVDD11_S3_P1")
		)
		(pad "2" smd circle
			(at 0.40005 0 180)
			(size 0 0)
			(layers "F.Cu" "F.Mask" "F.Paste")
			(net "GND")
		)
	)
	(footprint ""
		(layer "F.Cu")
		(at 423.796206 -402.7424 -90)
		(property "Reference" "R1061"
			(at 0 0 270)
			(layer "F.SilkS")
			(hide yes)
			(effects
				(font
					(size 1.27 1.27)
				)
			)
		)
		(property "Value" ""
			(at 0 0 270)
			(layer "F.Fab")
			(effects
				(font
					(size 1.27 1.27)
				)
			)
		)
		(duplicate_pad_numbers_are_jumpers no)
		(fp_line
			(start -0.32512 0.175006)
			(end -0.32512 -0.175006)
			(stroke
				(width 0.1)
				(type default)
			)
			(layer "F.Fab")
		)
		(fp_line
			(start 0.32512 0.175006)
			(end -0.32512 0.175006)
			(stroke
				(width 0.1)
				(type default)
			)
			(layer "F.Fab")
		)
		(fp_line
			(start -0.32512 -0.175006)
			(end 0.32512 -0.175006)
			(stroke
				(width 0.1)
				(type default)
			)
			(layer "F.Fab")
		)
		(fp_line
			(start 0.32512 -0.175006)
			(end 0.32512 0.175006)
			(stroke
				(width 0.1)
				(type default)
			)
			(layer "F.Fab")
		)
		(pad "1" smd rect
			(at -0.2667 0 270)
			(size 0.3048 0.381)
			(layers "F.Cu" "F.Mask" "F.Paste")
			(net "RST_RT_CPU0_P2_PERST_R_N")
		)
		(pad "2" smd rect
			(at 0.2667 0 90)
			(size 0.3048 0.381)
			(layers "F.Cu" "F.Mask" "F.Paste")
			(net "GND")
		)
	)
	(footprint ""
		(layer "F.Cu")
		(at 353.185222 -424.279314)
		(property "Reference" "C18"
			(at 0 0 0)
			(layer "F.SilkS")
			(hide yes)
			(effects
				(font
					(size 1.27 1.27)
				)
			)
		)
		(property "Value" ""
			(at 0 0 0)
			(layer "F.Fab")
			(effects
				(font
					(size 1.27 1.27)
				)
			)
		)
		(duplicate_pad_numbers_are_jumpers no)
		(fp_line
			(start -0.7874 -0.4064)
			(end 0.7874 -0.4064)
			(stroke
				(width 0.1524)
				(type default)
			)
			(layer "F.SilkS")
		)
		(fp_line
			(start -0.7874 0.4064)
			(end -0.7874 -0.4064)
			(stroke
				(width 0.1524)
				(type default)
			)
			(layer "F.SilkS")
		)
		(fp_line
			(start 0.7874 -0.4064)
			(end 0.7874 0.4064)
			(stroke
				(width 0.1524)
				(type default)
			)
			(layer "F.SilkS")
		)
		(fp_line
			(start 0.7874 0.4064)
			(end -0.7874 0.4064)
			(stroke
				(width 0.1524)
				(type default)
			)
			(layer "F.SilkS")
		)
		(fp_line
			(start -0.67945 -0.305054)
			(end -0.12065 -0.305054)
			(stroke
				(width 0.1)
				(type default)
			)
			(layer "F.Fab")
		)
		(fp_line
			(start -0.67945 0.3048)
			(end -0.67945 -0.305054)
			(stroke
				(width 0.1)
				(type default)
			)
			(layer "F.Fab")
		)
		(fp_line
			(start -0.12065 -0.305054)
			(end -0.12065 -0.2794)
			(stroke
				(width 0.1)
				(type default)
			)
			(layer "F.Fab")
		)
		(fp_line
			(start -0.12065 -0.2794)
			(end 0.12065 -0.2794)
			(stroke
				(width 0.1)
				(type default)
			)
			(layer "F.Fab")
		)
		(fp_line
			(start -0.12065 0.2794)
			(end -0.12065 0.3048)
			(stroke
				(width 0.1)
				(type default)
			)
			(layer "F.Fab")
		)
		(fp_line
			(start -0.12065 0.3048)
			(end -0.67945 0.3048)
			(stroke
				(width 0.1)
				(type default)
			)
			(layer "F.Fab")
		)
		(fp_line
			(start 0.120396 0.2794)
			(end -0.12065 0.2794)
			(stroke
				(width 0.1)
				(type default)
			)
			(layer "F.Fab")
		)
		(fp_line
			(start 0.120396 0.3048)
			(end 0.120396 0.2794)
			(stroke
				(width 0.1)
				(type default)
			)
			(layer "F.Fab")
		)
		(fp_line
			(start 0.12065 -0.3048)
			(end 0.67945 -0.3048)
			(stroke
				(width 0.1)
				(type default)
			)
			(layer "F.Fab")
		)
		(fp_line
			(start 0.12065 -0.2794)
			(end 0.12065 -0.3048)
			(stroke
				(width 0.1)
				(type default)
			)
			(layer "F.Fab")
		)
		(fp_line
			(start 0.67945 -0.3048)
			(end 0.67945 0.3048)
			(stroke
				(width 0.1)
				(type default)
			)
			(layer "F.Fab")
		)
		(fp_line
			(start 0.67945 0.3048)
			(end 0.120396 0.3048)
			(stroke
				(width 0.1)
				(type default)
			)
			(layer "F.Fab")
		)
		(pad "1" smd circle
			(at -0.40005 0)
			(size 0 0)
			(layers "F.Cu" "F.Mask" "F.Paste")
			(net "SWB_HSC_PWRGD_ISO")
		)
		(pad "2" smd circle
			(at 0.40005 0)
			(size 0 0)
			(layers "F.Cu" "F.Mask" "F.Paste")
			(net "GND")
		)
	)
	(footprint ""
		(layer "F.Cu")
		(at 204.994764 -95.695262)
		(property "Reference" "R1132"
			(at 0 0 0)
			(layer "F.SilkS")
			(hide yes)
			(effects
				(font
					(size 1.27 1.27)
				)
			)
		)
		(property "Value" ""
			(at 0 0 0)
			(layer "F.Fab")
			(effects
				(font
					(size 1.27 1.27)
				)
			)
		)
		(duplicate_pad_numbers_are_jumpers no)
		(fp_line
			(start -0.7874 -0.4064)
			(end 0.7874 -0.4064)
			(stroke
				(width 0.1524)
				(type default)
			)
			(layer "F.SilkS")
		)
		(fp_line
			(start -0.7874 0.4064)
			(end -0.7874 -0.4064)
			(stroke
				(width 0.1524)
				(type default)
			)
			(layer "F.SilkS")
		)
		(fp_line
			(start 0.7874 -0.4064)
			(end 0.7874 0.4064)
			(stroke
				(width 0.1524)
				(type default)
			)
			(layer "F.SilkS")
		)
		(fp_line
			(start 0.7874 0.4064)
			(end -0.7874 0.4064)
			(stroke
				(width 0.1524)
				(type default)
			)
			(layer "F.SilkS")
		)
		(fp_line
			(start -0.67945 -0.305054)
			(end -0.12065 -0.305054)
			(stroke
				(width 0.1)
				(type default)
			)
			(layer "F.Fab")
		)
		(fp_line
			(start -0.67945 0.3048)
			(end -0.67945 -0.305054)
			(stroke
				(width 0.1)
				(type default)
			)
			(layer "F.Fab")
		)
		(fp_line
			(start -0.12065 -0.305054)
			(end -0.12065 -0.2794)
			(stroke
				(width 0.1)
				(type default)
			)
			(layer "F.Fab")
		)
		(fp_line
			(start -0.12065 -0.2794)
			(end 0.12065 -0.2794)
			(stroke
				(width 0.1)
				(type default)
			)
			(layer "F.Fab")
		)
		(fp_line
			(start -0.12065 0.2794)
			(end -0.12065 0.3048)
			(stroke
				(width 0.1)
				(type default)
			)
			(layer "F.Fab")
		)
		(fp_line
			(start -0.12065 0.3048)
			(end -0.67945 0.3048)
			(stroke
				(width 0.1)
				(type default)
			)
			(layer "F.Fab")
		)
		(fp_line
			(start 0.120396 0.2794)
			(end -0.12065 0.2794)
			(stroke
				(width 0.1)
				(type default)
			)
			(layer "F.Fab")
		)
		(fp_line
			(start 0.120396 0.3048)
			(end 0.120396 0.2794)
			(stroke
				(width 0.1)
				(type default)
			)
			(layer "F.Fab")
		)
		(fp_line
			(start 0.12065 -0.3048)
			(end 0.67945 -0.3048)
			(stroke
				(width 0.1)
				(type default)
			)
			(layer "F.Fab")
		)
		(fp_line
			(start 0.12065 -0.2794)
			(end 0.12065 -0.3048)
			(stroke
				(width 0.1)
				(type default)
			)
			(layer "F.Fab")
		)
		(fp_line
			(start 0.67945 -0.3048)
			(end 0.67945 0.3048)
			(stroke
				(width 0.1)
				(type default)
			)
			(layer "F.Fab")
		)
		(fp_line
			(start 0.67945 0.3048)
			(end 0.120396 0.3048)
			(stroke
				(width 0.1)
				(type default)
			)
			(layer "F.Fab")
		)
		(pad "1" smd circle
			(at -0.40005 0)
			(size 0 0)
			(layers "F.Cu" "F.Mask" "F.Paste")
			(net "P12V_OCP_V3_1_PLD_R_PWRGD")
		)
		(pad "2" smd circle
			(at 0.40005 0)
			(size 0 0)
			(layers "F.Cu" "F.Mask" "F.Paste")
			(net "P12V_OCP_V3_1_PLD_PWRGD")
		)
	)
	(footprint ""
		(layer "F.Cu")
		(at 257.85953 -58.527442 180)
		(property "Reference" "R3974"
			(at 0 0 180)
			(layer "F.SilkS")
			(hide yes)
			(effects
				(font
					(size 1.27 1.27)
				)
			)
		)
		(property "Value" ""
			(at 0 0 180)
			(layer "F.Fab")
			(effects
				(font
					(size 1.27 1.27)
				)
			)
		)
		(duplicate_pad_numbers_are_jumpers no)
		(fp_line
			(start 0.7874 0.4064)
			(end -0.7874 0.4064)
			(stroke
				(width 0.1524)
				(type default)
			)
			(layer "F.SilkS")
		)
		(fp_line
			(start 0.7874 -0.4064)
			(end 0.7874 0.4064)
			(stroke
				(width 0.1524)
				(type default)
			)
			(layer "F.SilkS")
		)
		(fp_line
			(start -0.7874 0.4064)
			(end -0.7874 -0.4064)
			(stroke
				(width 0.1524)
				(type default)
			)
			(layer "F.SilkS")
		)
		(fp_line
			(start -0.7874 -0.4064)
			(end 0.7874 -0.4064)
			(stroke
				(width 0.1524)
				(type default)
			)
			(layer "F.SilkS")
		)
		(fp_line
			(start 0.67945 0.3048)
			(end 0.120396 0.3048)
			(stroke
				(width 0.1)
				(type default)
			)
			(layer "F.Fab")
		)
		(fp_line
			(start 0.67945 -0.3048)
			(end 0.67945 0.3048)
			(stroke
				(width 0.1)
				(type default)
			)
			(layer "F.Fab")
		)
		(fp_line
			(start 0.12065 -0.2794)
			(end 0.12065 -0.3048)
			(stroke
				(width 0.1)
				(type default)
			)
			(layer "F.Fab")
		)
		(fp_line
			(start 0.12065 -0.3048)
			(end 0.67945 -0.3048)
			(stroke
				(width 0.1)
				(type default)
			)
			(layer "F.Fab")
		)
		(fp_line
			(start 0.120396 0.3048)
			(end 0.120396 0.2794)
			(stroke
				(width 0.1)
				(type default)
			)
			(layer "F.Fab")
		)
		(fp_line
			(start 0.120396 0.2794)
			(end -0.12065 0.2794)
			(stroke
				(width 0.1)
				(type default)
			)
			(layer "F.Fab")
		)
		(fp_line
			(start -0.12065 0.3048)
			(end -0.67945 0.3048)
			(stroke
				(width 0.1)
				(type default)
			)
			(layer "F.Fab")
		)
		(fp_line
			(start -0.12065 0.2794)
			(end -0.12065 0.3048)
			(stroke
				(width 0.1)
				(type default)
			)
			(layer "F.Fab")
		)
		(fp_line
			(start -0.12065 -0.2794)
			(end 0.12065 -0.2794)
			(stroke
				(width 0.1)
				(type default)
			)
			(layer "F.Fab")
		)
		(fp_line
			(start -0.12065 -0.305054)
			(end -0.12065 -0.2794)
			(stroke
				(width 0.1)
				(type default)
			)
			(layer "F.Fab")
		)
		(fp_line
			(start -0.67945 0.3048)
			(end -0.67945 -0.305054)
			(stroke
				(width 0.1)
				(type default)
			)
			(layer "F.Fab")
		)
		(fp_line
			(start -0.67945 -0.305054)
			(end -0.12065 -0.305054)
			(stroke
				(width 0.1)
				(type default)
			)
			(layer "F.Fab")
		)
		(pad "1" smd rect
			(at -0.40005 0)
			(size 0.4572 0.508)
			(layers "F.Cu" "F.Mask" "F.Paste")
			(net "P12V_E1S_SENSE_0")
		)
		(pad "2" smd rect
			(at 0.40005 0)
			(size 0.4572 0.508)
			(layers "F.Cu" "F.Mask" "F.Paste")
			(net "P12V_E1S_0_ISENSE_MAM_MAM")
		)
	)
	(footprint ""
		(layer "F.Cu")
		(at 333.754476 -340.185248)
		(property "Reference" "PR78"
			(at 0 0 0)
			(layer "F.SilkS")
			(hide yes)
			(effects
				(font
					(size 1.27 1.27)
				)
			)
		)
		(property "Value" ""
			(at 0 0 0)
			(layer "F.Fab")
			(effects
				(font
					(size 1.27 1.27)
				)
			)
		)
		(duplicate_pad_numbers_are_jumpers no)
		(fp_line
			(start -0.7874 -0.4064)
			(end 0.7874 -0.4064)
			(stroke
				(width 0.1524)
				(type default)
			)
			(layer "F.SilkS")
		)
		(fp_line
			(start -0.7874 0.4064)
			(end -0.7874 -0.4064)
			(stroke
				(width 0.1524)
				(type default)
			)
			(layer "F.SilkS")
		)
		(fp_line
			(start 0.7874 -0.4064)
			(end 0.7874 0.4064)
			(stroke
				(width 0.1524)
				(type default)
			)
			(layer "F.SilkS")
		)
		(fp_line
			(start 0.7874 0.4064)
			(end -0.7874 0.4064)
			(stroke
				(width 0.1524)
				(type default)
			)
			(layer "F.SilkS")
		)
		(fp_line
			(start -0.67945 -0.305054)
			(end -0.12065 -0.305054)
			(stroke
				(width 0.1)
				(type default)
			)
			(layer "F.Fab")
		)
		(fp_line
			(start -0.67945 0.3048)
			(end -0.67945 -0.305054)
			(stroke
				(width 0.1)
				(type default)
			)
			(layer "F.Fab")
		)
		(fp_line
			(start -0.12065 -0.305054)
			(end -0.12065 -0.2794)
			(stroke
				(width 0.1)
				(type default)
			)
			(layer "F.Fab")
		)
		(fp_line
			(start -0.12065 -0.2794)
			(end 0.12065 -0.2794)
			(stroke
				(width 0.1)
				(type default)
			)
			(layer "F.Fab")
		)
		(fp_line
			(start -0.12065 0.2794)
			(end -0.12065 0.3048)
			(stroke
				(width 0.1)
				(type default)
			)
			(layer "F.Fab")
		)
		(fp_line
			(start -0.12065 0.3048)
			(end -0.67945 0.3048)
			(stroke
				(width 0.1)
				(type default)
			)
			(layer "F.Fab")
		)
		(fp_line
			(start 0.120396 0.2794)
			(end -0.12065 0.2794)
			(stroke
				(width 0.1)
				(type default)
			)
			(layer "F.Fab")
		)
		(fp_line
			(start 0.120396 0.3048)
			(end 0.120396 0.2794)
			(stroke
				(width 0.1)
				(type default)
			)
			(layer "F.Fab")
		)
		(fp_line
			(start 0.12065 -0.3048)
			(end 0.67945 -0.3048)
			(stroke
				(width 0.1)
				(type default)
			)
			(layer "F.Fab")
		)
		(fp_line
			(start 0.12065 -0.2794)
			(end 0.12065 -0.3048)
			(stroke
				(width 0.1)
				(type default)
			)
			(layer "F.Fab")
		)
		(fp_line
			(start 0.67945 -0.3048)
			(end 0.67945 0.3048)
			(stroke
				(width 0.1)
				(type default)
			)
			(layer "F.Fab")
		)
		(fp_line
			(start 0.67945 0.3048)
			(end 0.120396 0.3048)
			(stroke
				(width 0.1)
				(type default)
			)
			(layer "F.Fab")
		)
		(pad "1" smd circle
			(at -0.40005 0)
			(size 0 0)
			(layers "F.Cu" "F.Mask" "F.Paste")
			(net "PVDDCR_CPU1_P0_LSET1")
		)
		(pad "2" smd circle
			(at 0.40005 0)
			(size 0 0)
			(layers "F.Cu" "F.Mask" "F.Paste")
			(net "GND")
		)
	)
)
